#ISCELL
  mstr_misc dns *
  *
#ISCELL
  pure_quanta quanta_title_block_c *
  *
#ISCELL
  logical_power universal_gnd *
  page248_i1
#CELL
  pure_quanta q_res *
  page248_i10
#CELL
  pure_quanta rs53319lr *
  page248_i11
#ISCELL
  logical_power universal_gnd *
  page248_i12
#ISCELL
  logical_power universal_gnd *
  page248_i13
#CELL
  pure_quanta q_cap *
  page248_i14
#ISCELL
  logical_power universal_gnd *
  page248_i15
#CELL
  pure_quanta q_cap *
  page248_i16
#ISCELL
  logical_power gnd *
  page248_i17
#CELL
  pure_quanta q_cap *
  page248_i18
#CELL
  pure_quanta q_inductor *
  page248_i19
#CELL
  pure_quanta q_cap *
  page248_i2
#ISCELL
  logical_power vccaux15 *
  page248_i20
#ISCELL
  standard offpage *
  page248_i21
#ISCELL
  logical_power universal_gnd *
  page248_i22
#CELL
  pure_quanta q_capp *
  page248_i23
#ISCELL
  logical_power vccaux15 *
  page248_i24
#CELL
  pure_quanta q_cap *
  page248_i25
#CELL
  pure_quanta q_res *
  page248_i26
#CELL
  pure_quanta q_res *
  page248_i27
#CELL
  pure_quanta q_cap *
  page248_i28
#CELL
  pure_quanta q_cap *
  page248_i29
#CELL
  pure_quanta q_res *
  page248_i3
#CELL
  pure_quanta q_cap *
  page248_i30
#CELL
  pure_quanta q_cap *
  page248_i31
#CELL
  pure_quanta q_res *
  page248_i32
#ISCELL
  logical_power universal_power *
  page248_i33
#CELL
  pure_quanta q_res *
  page248_i34
#CELL
  pure_quanta q_cap *
  page248_i35
#CELL
  pure_quanta q_res *
  page248_i36
#CELL
  pure_quanta q_cap *
  page248_i37
#CELL
  pure_quanta q_cap *
  page248_i38
#ISCELL
  logical_power universal_gnd *
  page248_i39
#ISCELL
  logical_power universal_power *
  page248_i4
#CELL
  pure_quanta q_capp *
  page248_i40
#CELL
  pure_quanta q_capp *
  page248_i41
#CELL
  pure_quanta q_short *
  page248_i42
#CELL
  pure_quanta q_short *
  page248_i43
#CELL
  pure_quanta q_cap *
  page248_i44
#CELL
  pure_quanta q_cap *
  page248_i45
#ISCELL
  logical_power universal_gnd *
  page248_i46
#CELL
  pure_quanta q_capp *
  page248_i47
#CELL
  pure_quanta q_capp *
  page248_i48
#ISCELL
  logical_power vccaux15 *
  page248_i49
#ISCELL
  logical_power universal_gnd *
  page248_i5
#ISCELL
  logical_power universal_gnd *
  page248_i50
#CELL
  pure_quanta q_res *
  page248_i51
#CELL
  pure_quanta q_res *
  page248_i52
#CELL
  pure_quanta q_inductor *
  page248_i53
#ISCELL
  standard offpage *
  page248_i54
#ISCELL
  standard offpage *
  page248_i55
#ISCELL
  logical_power universal_power *
  page248_i56
#CELL
  pure_quanta q_res *
  page248_i6
#ISCELL
  logical_power universal_gnd *
  page248_i7
#CELL
  pure_quanta q_cap *
  page248_i8
#CELL
  pure_quanta q_res *
  page248_i9
